# BASEBOARD_FAB2 (Tioga Pass) — schematic netlist excerpt (pin names and nets, part order shuffled) for the footprints in the layout excerpt that follows; sources: Cadence DE-HDL packaged netlist, KiCad conversion of Wiwynn_Tioga_Pass_MB.brd

R6D8  RES  49.9 1% CHIP  pkg 0402  page 96 : A = PVCCIO_CPU0 ; B = PWRGD_CPU0_G
C4E11  CAP_A  22.0UF 4V 20% X6S  pkg 0603V  page 202 : A = PVCCIN_CPU0 ; B = GND

U9A5  74CBTLV1G125  IC  pkg SMLF  page 113
  OE_N  = FM_CPU0_OR_CPU1_MCP_PRES
  A  = JTAG_MCP_TCK_R1
  B  = GND

(kicad_pcb
	(version 20260206)
	(generator "pcbnew")
	(generator_version "10.0")
	(general
		(thickness 1.6)
		(legacy_teardrops no)
	)
	(paper "A4")
	(title_block
		(title "Wiwynn_Tioga_Pass_MB.brd")
		(comment 1 "Tioga Pass / footprints 529-531 of 4770")
	)
	(layers
		(0 "F.Cu" signal "TOP")
		(4 "In1.Cu" signal "L2GND")
		(6 "In2.Cu" signal "L3")
		(8 "In3.Cu" signal "L4GND")
		(10 "In4.Cu" signal "L5")
		(12 "In5.Cu" signal "L6GND")
		(14 "In6.Cu" signal "L7VCC")
		(16 "In7.Cu" signal "L8VCC")
		(18 "In8.Cu" signal "L9GND")
		(20 "In9.Cu" signal "L10")
		(22 "In10.Cu" signal "L11GND")
		(24 "In11.Cu" signal "L12")
		(26 "In12.Cu" signal "L13GND")
		(2 "B.Cu" signal "BOTTOM")
		(9 "F.Adhes" user "F.Adhesive")
		(11 "B.Adhes" user "B.Adhesive")
		(13 "F.Paste" user "Package Geometry/Pastemask Top")
		(15 "B.Paste" user "Package Geometry/Pastemask Bottom")
		(5 "F.SilkS" user "Ref Des/Silkscreen Top")
		(7 "B.SilkS" user "Ref Des/Silkscreen Bottom")
		(1 "F.Mask" user "Board Geometry/Soldermask Top")
		(3 "B.Mask" user "Board Geometry/Soldermask Bottom")
		(17 "Dwgs.User" user "User.Drawings")
		(19 "Cmts.User" user "User.Comments")
		(21 "Eco1.User" user "User.Eco1")
		(23 "Eco2.User" user "User.Eco2")
		(25 "Edge.Cuts" user "Board Geometry/Outline")
		(27 "Margin" user)
		(31 "F.CrtYd" user "Package Geometry/Place Bound Top")
		(29 "B.CrtYd" user "Package Geometry/Place Bound Bottom")
		(35 "F.Fab" user "Ref Des/Assembly Top")
		(33 "B.Fab" user "Ref Des/Assembly Bottom")
	)
	(footprint ""
		(layer "F.Cu")
		(at 214.503 -59.17692 180)
		(property "Reference" "C4E11"
			(at 0 0 180)
			(layer "F.SilkS")
			(hide yes)
			(effects
				(font
					(size 1.27 1.27)
				)
			)
		)
		(property "Value" ""
			(at 0 0 180)
			(layer "F.Fab")
			(effects
				(font
					(size 1.27 1.27)
				)
			)
		)
		(duplicate_pad_numbers_are_jumpers no)
		(fp_poly
			(pts
				(xy -0.4953 -0.2032) (xy 0.4953 -0.2032) (xy 0.4953 1.6002) (xy -0.4953 1.6002)
			)
			(stroke
				(width 0)
				(type default)
			)
			(fill no)
			(layer "F.CrtYd")
		)
		(fp_line
			(start 0.4953 1.6002)
			(end -0.4953 1.6002)
			(stroke
				(width 0.1)
				(type default)
			)
			(layer "F.Fab")
		)
		(fp_line
			(start 0.4953 -0.2032)
			(end 0.4953 1.6002)
			(stroke
				(width 0.1)
				(type default)
			)
			(layer "F.Fab")
		)
		(fp_line
			(start -0.4953 1.6002)
			(end -0.4953 -0.2032)
			(stroke
				(width 0.1)
				(type default)
			)
			(layer "F.Fab")
		)
		(fp_line
			(start -0.4953 -0.2032)
			(end 0.4953 -0.2032)
			(stroke
				(width 0.1)
				(type default)
			)
			(layer "F.Fab")
		)
		(pad "1" smd rect
			(at 0 0 180)
			(size 0.762 0.889)
			(layers "F.Cu" "F.Mask" "F.Paste")
			(net "PVCCIN_CPU0")
		)
		(pad "2" smd rect
			(at 0 1.397 180)
			(size 0.762 0.889)
			(layers "F.Cu" "F.Mask" "F.Paste")
			(net "GND")
		)
		(zone
			(layer "F.Cu")
			(hatch none 0.5)
			(connect_pads
				(clearance 0)
			)
			(min_thickness 0.25)
			(keepout
				(tracks not_allowed)
				(vias allowed)
				(pads allowed)
				(copperpour not_allowed)
				(footprints allowed)
			)
			(placement
				(enabled no)
				(sheetname "")
			)
			(fill
				(thermal_gap 0.5)
				(thermal_bridge_width 0.5)
				(island_removal_mode 0)
			)
			(polygon
				(pts
					(xy 214.884 -59.62142) (xy 214.122 -59.62142) (xy 214.122 -60.12942) (xy 214.884 -60.12942)
				)
			)
		)
	)
	(footprint ""
		(layer "F.Cu")
		(at 466.344 -137.033 90)
		(property "Reference" "U9A5"
			(at -0.51816 2.26949 90)
			(unlocked yes)
			(layer "F.SilkS")
			(effects
				(font
					(size 0.7874 0.5842)
					(thickness 0.1524)
				)
				(justify left)
			)
		)
		(property "Value" ""
			(at 0 0 90)
			(layer "F.Fab")
			(effects
				(font
					(size 1.27 1.27)
				)
			)
		)
		(duplicate_pad_numbers_are_jumpers no)
		(fp_circle
			(center -0.4699 -0.8382)
			(end -0.4699 -0.7112)
			(stroke
				(width 0.254)
				(type default)
			)
			(fill no)
			(layer "F.SilkS")
		)
		(fp_poly
			(pts
				(xy 0.21463 -0.450088) (xy 1.56337 -0.450088) (xy 1.56337 1.75006) (xy 0.21463 1.75006)
			)
			(stroke
				(width 0)
				(type default)
			)
			(fill no)
			(layer "F.CrtYd")
		)
		(fp_line
			(start 1.56337 -0.450088)
			(end 1.56337 1.75006)
			(stroke
				(width 0.1)
				(type default)
			)
			(layer "F.Fab")
		)
		(fp_line
			(start 0.21463 -0.450088)
			(end 1.56337 -0.450088)
			(stroke
				(width 0.1)
				(type default)
			)
			(layer "F.Fab")
		)
		(fp_line
			(start 1.56337 1.75006)
			(end 0.21463 1.75006)
			(stroke
				(width 0.1)
				(type default)
			)
			(layer "F.Fab")
		)
		(fp_line
			(start 0.21463 1.75006)
			(end 0.21463 -0.450088)
			(stroke
				(width 0.1)
				(type default)
			)
			(layer "F.Fab")
		)
		(fp_circle
			(center -0.4699 -0.8382)
			(end -0.4699 -0.7112)
			(stroke
				(width 0.254)
				(type default)
			)
			(fill no)
			(layer "F.Fab")
		)
		(pad "1" smd rect
			(at 0 0 90)
			(size 1.016 0.381)
			(layers "F.Cu" "F.Mask" "F.Paste")
			(net "FM_CPU0_OR_CPU1_MCP_PRES")
		)
		(pad "2" smd rect
			(at 0 0.649986 90)
			(size 1.016 0.381)
			(layers "F.Cu" "F.Mask" "F.Paste")
			(net "JTAG_MCP_TCK_R1")
		)
		(pad "3" smd rect
			(at 0 1.299972 90)
			(size 1.016 0.381)
			(layers "F.Cu" "F.Mask" "F.Paste")
			(net "GND")
		)
		(pad "4" smd rect
			(at 1.778 1.299972 90)
			(size 1.016 0.381)
			(layers "F.Cu" "F.Mask" "F.Paste")
			(net "GND")
		)
		(pad "5" smd rect
			(at 1.778 0 90)
			(size 1.016 0.381)
			(layers "F.Cu" "F.Mask" "F.Paste")
			(net "P3V3_STBY")
		)
	)
	(footprint ""
		(layer "F.Cu")
		(at 281.178 -74.041 90)
		(property "Reference" "R6D8"
			(at 0 0 90)
			(layer "F.SilkS")
			(hide yes)
			(effects
				(font
					(size 1.27 1.27)
				)
			)
		)
		(property "Value" ""
			(at 0 0 90)
			(layer "F.Fab")
			(effects
				(font
					(size 1.27 1.27)
				)
			)
		)
		(duplicate_pad_numbers_are_jumpers no)
		(fp_rect
			(start -0.2794 -0.1016)
			(end 0.2794 0.9906)
			(stroke
				(width 0)
				(type default)
			)
			(fill no)
			(layer "F.CrtYd")
		)
		(fp_line
			(start 0.2794 -0.1016)
			(end -0.2794 -0.1016)
			(stroke
				(width 0.1)
				(type default)
			)
			(layer "F.Fab")
		)
		(fp_line
			(start -0.2794 -0.1016)
			(end -0.2794 0.9906)
			(stroke
				(width 0.1)
				(type default)
			)
			(layer "F.Fab")
		)
		(fp_line
			(start 0.2794 0.9906)
			(end 0.2794 -0.1016)
			(stroke
				(width 0.1)
				(type default)
			)
			(layer "F.Fab")
		)
		(fp_line
			(start -0.2794 0.9906)
			(end 0.2794 0.9906)
			(stroke
				(width 0.1)
				(type default)
			)
			(layer "F.Fab")
		)
		(pad "1" smd rect
			(at 0 0 90)
			(size 0.508 0.508)
			(layers "F.Cu" "F.Mask" "F.Paste")
			(net "PVCCIO_CPU0")
		)
		(pad "2" smd rect
			(at 0 0.889 90)
			(size 0.508 0.508)
			(layers "F.Cu" "F.Mask" "F.Paste")
			(net "PWRGD_CPU0_G")
		)
		(zone
			(layer "F.Cu")
			(hatch none 0.5)
			(connect_pads
				(clearance 0)
			)
			(min_thickness 0.25)
			(keepout
				(tracks allowed)
				(vias not_allowed)
				(pads allowed)
				(copperpour not_allowed)
				(footprints allowed)
			)
			(placement
				(enabled no)
				(sheetname "")
			)
			(fill
				(thermal_gap 0.5)
				(thermal_bridge_width 0.5)
				(island_removal_mode 0)
			)
			(polygon
				(pts
					(xy 281.432 -73.787) (xy 281.813 -73.787) (xy 281.813 -74.295) (xy 281.432 -74.295)
				)
			)
		)
		(zone
			(layer "F.Cu")
			(hatch none 0.5)
			(connect_pads
				(clearance 0)
			)
			(min_thickness 0.25)
			(keepout
				(tracks not_allowed)
				(vias allowed)
				(pads allowed)
				(copperpour not_allowed)
				(footprints allowed)
			)
			(placement
				(enabled no)
				(sheetname "")
			)
			(fill
				(thermal_gap 0.5)
				(thermal_bridge_width 0.5)
				(island_removal_mode 0)
			)
			(polygon
				(pts
					(xy 281.432 -73.787) (xy 281.813 -73.787) (xy 281.813 -74.295) (xy 281.432 -74.295)
				)
			)
		)
	)
)
